# TIMECARD (Time Appliance Project (Time Card)) — schematic netlist excerpt (pin names and nets, part order shuffled) for the footprints in the layout excerpt that follows; sources: Cadence DE-HDL packaged netlist, KiCad conversion of R4006-B0001-02_R01.brd

R468  RESISTOR  33OHM 1%  pkg SMC_0402R_H016  page 24 : \1\ = R_FT4232_TDI ; \2\ = FT4232_TDI_MOSI
C152  CAPACITOR  0.1UF 10V 10%  pkg SMC_0402R_H022  page 14 : \1\ = XP1R0V_FPGA_VCCINT ; \2\ = SG

(kicad_pcb
	(version 20260206)
	(generator "pcbnew")
	(generator_version "10.0")
	(general
		(thickness 1.6)
		(legacy_teardrops no)
	)
	(paper "A4")
	(title_block
		(title "timecard-production-celestica-r4006 — R4006-B0001-02_R01.brd")
		(comment 1 "Time Appliance Project (Time Card) / footprints 851-852 of 1113")
	)
	(layers
		(0 "F.Cu" signal "TOP")
		(4 "In1.Cu" signal "L02_GND1")
		(6 "In2.Cu" signal "L03_SIG1")
		(8 "In3.Cu" signal "L04_GND2")
		(10 "In4.Cu" signal "L05_VCC1")
		(12 "In5.Cu" signal "L06_VCC2")
		(14 "In6.Cu" signal "L07_GND3")
		(16 "In7.Cu" signal "L08_SIG2")
		(18 "In8.Cu" signal "L09_GND4")
		(2 "B.Cu" signal "BOTTOM")
		(9 "F.Adhes" user "F.Adhesive")
		(11 "B.Adhes" user "B.Adhesive")
		(13 "F.Paste" user "Package Geometry/Pastemask Top")
		(15 "B.Paste" user "Package Geometry/Pastemask Bottom")
		(5 "F.SilkS" user "Ref Des/Silkscreen Top")
		(7 "B.SilkS" user "Ref Des/Silkscreen Bottom")
		(1 "F.Mask" user "Board Geometry/Soldermask Top")
		(3 "B.Mask" user "Board Geometry/Soldermask Bottom")
		(17 "Dwgs.User" user "User.Drawings")
		(19 "Cmts.User" user "User.Comments")
		(21 "Eco1.User" user "User.Eco1")
		(23 "Eco2.User" user "User.Eco2")
		(25 "Edge.Cuts" user "Board Geometry/Outline")
		(27 "Margin" user)
		(31 "F.CrtYd" user "Package Geometry/Place Bound Top")
		(29 "B.CrtYd" user "Package Geometry/Place Bound Bottom")
		(35 "F.Fab" user "Ref Des/Assembly Top")
		(33 "B.Fab" user "Ref Des/Assembly Bottom")
	)
	(footprint ""
		(layer "B.Cu")
		(at 113.847118 -40.323008 90)
		(property "Reference" "C152"
			(at -1.397508 -42.017188 270)
			(unlocked yes)
			(layer "B.SilkS")
			(effects
				(font
					(size 0.635 0.4064)
					(thickness 0.1524)
				)
				(justify mirror)
			)
		)
		(property "Value" "VAL*"
			(at 0 3.718306 90)
			(unlocked yes)
			(layer "B.Fab")
			(hide yes)
			(effects
				(font
					(size 0.7874 0.5842)
					(thickness 0.127)
				)
				(justify mirror)
			)
		)
		(property "Device Type" "CAPACITOR-G105-0B104-CK,0.1UF,A"
			(at 0 1.432306 90)
			(unlocked yes)
			(layer "B.Fab")
			(hide yes)
			(effects
				(font
					(size 0.7874 0.5842)
					(thickness 0.127)
				)
				(justify mirror)
			)
		)
		(property "User Part Number" "PARTNUM*"
			(at 0 2.575306 90)
			(unlocked yes)
			(layer "Cmts.User")
			(hide yes)
			(effects
				(font
					(size 0.7874 0.5842)
					(thickness 0.127)
				)
				(justify mirror)
			)
		)
		(property "Tolerance" "TOL*"
			(at 0 4.861306 90)
			(unlocked yes)
			(layer "Cmts.User")
			(hide yes)
			(effects
				(font
					(size 0.7874 0.5842)
					(thickness 0.127)
				)
				(justify mirror)
			)
		)
		(duplicate_pad_numbers_are_jumpers no)
		(fp_line
			(start 0.970026 -0.4699)
			(end -0.970026 -0.4699)
			(stroke
				(width 0.1)
				(type default)
			)
			(layer "B.SilkS")
		)
		(fp_line
			(start -0.970026 -0.4699)
			(end -0.970026 0.4699)
			(stroke
				(width 0.1)
				(type default)
			)
			(layer "B.SilkS")
		)
		(fp_line
			(start 0.970026 0.4699)
			(end 0.970026 -0.4699)
			(stroke
				(width 0.1)
				(type default)
			)
			(layer "B.SilkS")
		)
		(fp_line
			(start -0.970026 0.4699)
			(end 0.970026 0.4699)
			(stroke
				(width 0.1)
				(type default)
			)
			(layer "B.SilkS")
		)
		(fp_poly
			(pts
				(xy 0.970026 0.4699) (xy -0.970026 0.4699) (xy -0.970026 -0.4699) (xy 0.970026 -0.4699)
			)
			(stroke
				(width 0)
				(type default)
			)
			(fill no)
			(layer "B.CrtYd")
		)
		(fp_line
			(start 0.508 -0.3048)
			(end -0.508 -0.3048)
			(stroke
				(width 0.1)
				(type default)
			)
			(layer "B.Fab")
		)
		(fp_line
			(start -0.508 -0.3048)
			(end -0.508 0.3048)
			(stroke
				(width 0.1)
				(type default)
			)
			(layer "B.Fab")
		)
		(fp_line
			(start 0.508 0.3048)
			(end 0.508 -0.3048)
			(stroke
				(width 0.1)
				(type default)
			)
			(layer "B.Fab")
		)
		(fp_line
			(start -0.508 0.3048)
			(end 0.508 0.3048)
			(stroke
				(width 0.1)
				(type default)
			)
			(layer "B.Fab")
		)
		(pad "1" smd circle
			(at 0.500126 0 270)
			(size 0.635 0.635)
			(layers "B.Cu" "B.Mask" "B.Paste")
			(net "XP1R0V_FPGA_VCCINT")
		)
		(pad "2" smd circle
			(at -0.500126 0 270)
			(size 0.635 0.635)
			(layers "B.Cu" "B.Mask" "B.Paste")
			(net "SG")
		)
	)
	(footprint ""
		(layer "B.Cu")
		(at 22.4028 -90.7796 -90)
		(property "Reference" "R468"
			(at -2.5654 4.40817 270)
			(unlocked yes)
			(layer "B.SilkS")
			(effects
				(font
					(size 0.7874 0.5842)
					(thickness 0.1524)
				)
				(justify mirror)
			)
		)
		(property "Value" "VAL*"
			(at -0.02032 2.13233 270)
			(unlocked yes)
			(layer "B.Fab")
			(hide yes)
			(effects
				(font
					(size 0.7874 0.5842)
					(thickness 0.1524)
				)
				(justify mirror)
			)
		)
		(property "Tolerance" "TOL*"
			(at -0.044704 3.05435 270)
			(unlocked yes)
			(layer "Cmts.User")
			(hide yes)
			(effects
				(font
					(size 0.7874 0.5842)
					(thickness 0.1524)
				)
				(justify mirror)
			)
		)
		(property "User Part Number" "PARTNUM*"
			(at -0.02032 4.024884 270)
			(unlocked yes)
			(layer "Cmts.User")
			(hide yes)
			(effects
				(font
					(size 0.7874 0.5842)
					(thickness 0.1524)
				)
				(justify mirror)
			)
		)
		(property "Device Type" "RESISTOR-G155-133R0-01,33OHM,1%"
			(at -0.008382 1.210564 270)
			(unlocked yes)
			(layer "B.Fab")
			(hide yes)
			(effects
				(font
					(size 0.7874 0.5842)
					(thickness 0.1524)
				)
				(justify mirror)
			)
		)
		(duplicate_pad_numbers_are_jumpers no)
		(fp_line
			(start -1.143 0.5588)
			(end -1.143 -0.5588)
			(stroke
				(width 0.1)
				(type default)
			)
			(layer "B.SilkS")
		)
		(fp_line
			(start 1.143 0.5588)
			(end -1.143 0.5588)
			(stroke
				(width 0.1)
				(type default)
			)
			(layer "B.SilkS")
		)
		(fp_line
			(start -1.143 -0.5588)
			(end 1.143 -0.5588)
			(stroke
				(width 0.1)
				(type default)
			)
			(layer "B.SilkS")
		)
		(fp_line
			(start 1.143 -0.5588)
			(end 1.143 0.5588)
			(stroke
				(width 0.1)
				(type default)
			)
			(layer "B.SilkS")
		)
		(fp_poly
			(pts
				(xy 1.143 0.5588) (xy -1.143 0.5588) (xy -1.143 -0.5588) (xy 1.143 -0.5588)
			)
			(stroke
				(width 0)
				(type default)
			)
			(fill no)
			(layer "B.CrtYd")
		)
		(fp_line
			(start -0.508 0.3048)
			(end -0.508 -0.3048)
			(stroke
				(width 0.1)
				(type default)
			)
			(layer "B.Fab")
		)
		(fp_line
			(start 0.508 0.3048)
			(end -0.508 0.3048)
			(stroke
				(width 0.1)
				(type default)
			)
			(layer "B.Fab")
		)
		(fp_line
			(start -0.508 -0.3048)
			(end 0.508 -0.3048)
			(stroke
				(width 0.1)
				(type default)
			)
			(layer "B.Fab")
		)
		(fp_line
			(start 0.508 -0.3048)
			(end 0.508 0.3048)
			(stroke
				(width 0.1)
				(type default)
			)
			(layer "B.Fab")
		)
		(pad "1" smd rect
			(at 0.5334 0 90)
			(size 0.7112 0.6096)
			(layers "B.Cu" "B.Mask" "B.Paste")
			(net "R_FT4232_TDI")
		)
		(pad "2" smd rect
			(at -0.5334 0 90)
			(size 0.7112 0.6096)
			(layers "B.Cu" "B.Mask" "B.Paste")
			(net "FT4232_TDI_MOSI")
		)
		(zone
			(layer "B.Cu")
			(hatch none 0.5)
			(connect_pads
				(clearance 0)
			)
			(min_thickness 0.25)
			(keepout
				(tracks allowed)
				(vias not_allowed)
				(pads allowed)
				(copperpour not_allowed)
				(footprints allowed)
			)
			(placement
				(enabled no)
				(sheetname "")
			)
			(fill
				(thermal_gap 0.5)
				(thermal_bridge_width 0.5)
				(island_removal_mode 0)
			)
			(polygon
				(pts
					(xy 22.098 -90.7034) (xy 22.7076 -90.7034) (xy 22.7076 -90.8558) (xy 22.098 -90.8558)
				)
			)
		)
		(zone
			(layer "B.Cu")
			(hatch none 0.5)
			(connect_pads
				(clearance 0)
			)
			(min_thickness 0.25)
			(keepout
				(tracks not_allowed)
				(vias allowed)
				(pads allowed)
				(copperpour not_allowed)
				(footprints allowed)
			)
			(placement
				(enabled no)
				(sheetname "")
			)
			(fill
				(thermal_gap 0.5)
				(thermal_bridge_width 0.5)
				(island_removal_mode 0)
			)
			(polygon
				(pts
					(xy 22.098 -90.7034) (xy 22.7076 -90.7034) (xy 22.7076 -90.8558) (xy 22.098 -90.8558)
				)
			)
		)
	)
)
